(kicad_pcb
	(version 20260206)
	(generator "pcbnew")
	(generator_version "10.0")
	(general
		(thickness 1.6)
		(legacy_teardrops no)
	)
	(paper "A4")
	(title_block
		(title "Bryce Canyon_IOM_M2_16342-2_OCP.brd")
		(comment 1 "Bryce Canyon / footprints 512-518 of 1146")
	)
	(layers
		(0 "F.Cu" signal "TOP")
		(4 "In1.Cu" signal "L2GND")
		(6 "In2.Cu" signal "L3")
		(8 "In3.Cu" signal "L4VCC")
		(10 "In4.Cu" signal "L5VCC")
		(12 "In5.Cu" signal "L6")
		(14 "In6.Cu" signal "L7GND")
		(2 "B.Cu" signal "BOTTOM")
		(9 "F.Adhes" user "F.Adhesive")
		(11 "B.Adhes" user "B.Adhesive")
		(13 "F.Paste" user "Package Geometry/Pastemask Top")
		(15 "B.Paste" user "Package Geometry/Pastemask Bottom")
		(5 "F.SilkS" user "Ref Des/Silkscreen Top")
		(7 "B.SilkS" user "Ref Des/Silkscreen Bottom")
		(1 "F.Mask" user "Board Geometry/Soldermask Top")
		(3 "B.Mask" user "Board Geometry/Soldermask Bottom")
		(17 "Dwgs.User" user "User.Drawings")
		(19 "Cmts.User" user "User.Comments")
		(21 "Eco1.User" user "User.Eco1")
		(23 "Eco2.User" user "User.Eco2")
		(25 "Edge.Cuts" user "Board Geometry/Outline")
		(27 "Margin" user)
		(31 "F.CrtYd" user "Package Geometry/Place Bound Top")
		(29 "B.CrtYd" user "Package Geometry/Place Bound Bottom")
		(35 "F.Fab" user "Ref Des/Assembly Top")
		(33 "B.Fab" user "Ref Des/Assembly Bottom")
	)
	(footprint ""
		(layer "F.Cu")
		(at 88.092026 -132.68325)
		(property "Reference" "R138"
			(at 0 0 0)
			(layer "F.SilkS")
			(hide yes)
			(effects
				(font
					(size 1.27 1.27)
				)
			)
		)
		(property "Value" "8K2R2J-3-GP"
			(at 0.064008 -3.993896 0)
			(unlocked yes)
			(layer "F.Fab")
			(hide yes)
			(effects
				(font
					(size 1.016 1.016)
					(thickness 0.1524)
				)
			)
		)
		(property "Device Type" "R402H16"
			(at 0.064008 -5.517896 0)
			(unlocked yes)
			(layer "F.Fab")
			(hide yes)
			(effects
				(font
					(size 1.016 1.016)
					(thickness 0.1524)
				)
			)
		)
		(duplicate_pad_numbers_are_jumpers no)
		(fp_line
			(start -0.508 -0.9398)
			(end -0.508 0.9398)
			(stroke
				(width 0.1524)
				(type default)
			)
			(layer "F.SilkS")
		)
		(fp_line
			(start 0.508 -0.9398)
			(end -0.508 -0.9398)
			(stroke
				(width 0.1524)
				(type default)
			)
			(layer "F.SilkS")
		)
		(fp_rect
			(start -0.508 0.9398)
			(end 0.508 -0.9398)
			(stroke
				(width 0)
				(type default)
			)
			(fill no)
			(layer "F.CrtYd")
		)
		(fp_rect
			(start -0.508 0.9398)
			(end 0.508 -0.9398)
			(stroke
				(width 0)
				(type default)
			)
			(fill no)
			(layer "F.Fab")
		)
		(pad "1" smd custom
			(at 0 -0.4445)
			(size 0.1397 0.1397)
			(layers "F.Cu" "F.Mask" "F.Paste")
			(net "EEPROM_A2")
			(options
				(clearance outline)
				(anchor circle)
			)
			(primitives
				(gr_poly
					(pts
						(arc
							(start -0.1778 -0.2794)
							(mid -0.249642 -0.249642)
							(end -0.2794 -0.1778)
						)
						(arc
							(start -0.2794 0.1778)
							(mid -0.249642 0.249642)
							(end -0.1778 0.2794)
						)
						(arc
							(start 0.1778 0.2794)
							(mid 0.249642 0.249642)
							(end 0.2794 0.1778)
						)
						(arc
							(start 0.2794 -0.1778)
							(mid 0.249642 -0.249642)
							(end 0.1778 -0.2794)
						)
					)
					(width 0)
					(fill yes)
				)
			)
		)
		(pad "2" smd custom
			(at 0 0.4445)
			(size 0.1397 0.1397)
			(layers "F.Cu" "F.Mask" "F.Paste")
			(net "GND")
			(options
				(clearance outline)
				(anchor circle)
			)
			(primitives
				(gr_poly
					(pts
						(arc
							(start -0.1778 -0.2794)
							(mid -0.249642 -0.249642)
							(end -0.2794 -0.1778)
						)
						(arc
							(start -0.2794 0.1778)
							(mid -0.249642 0.249642)
							(end -0.1778 0.2794)
						)
						(arc
							(start 0.1778 0.2794)
							(mid 0.249642 0.249642)
							(end 0.2794 0.1778)
						)
						(arc
							(start 0.2794 -0.1778)
							(mid 0.249642 -0.249642)
							(end 0.1778 -0.2794)
						)
					)
					(width 0)
					(fill yes)
				)
			)
		)
	)
	(footprint ""
		(layer "F.Cu")
		(at 151.004016 -14.977618 180)
		(property "Reference" "R516"
			(at 0 0 180)
			(layer "F.SilkS")
			(hide yes)
			(effects
				(font
					(size 1.27 1.27)
				)
			)
		)
		(property "Value" "0R2J-2-GP"
			(at 0.064008 -3.993896 180)
			(unlocked yes)
			(layer "F.Fab")
			(hide yes)
			(effects
				(font
					(size 1.016 1.016)
					(thickness 0.1524)
				)
			)
		)
		(property "Device Type" "R402H16"
			(at 0.064008 -5.517896 180)
			(unlocked yes)
			(layer "F.Fab")
			(hide yes)
			(effects
				(font
					(size 1.016 1.016)
					(thickness 0.1524)
				)
			)
		)
		(duplicate_pad_numbers_are_jumpers no)
		(fp_line
			(start 0.508 -0.9398)
			(end -0.508 -0.9398)
			(stroke
				(width 0.1524)
				(type default)
			)
			(layer "F.SilkS")
		)
		(fp_line
			(start -0.508 -0.9398)
			(end -0.508 0.9398)
			(stroke
				(width 0.1524)
				(type default)
			)
			(layer "F.SilkS")
		)
		(fp_rect
			(start -0.508 0.9398)
			(end 0.508 -0.9398)
			(stroke
				(width 0)
				(type default)
			)
			(fill no)
			(layer "F.CrtYd")
		)
		(fp_rect
			(start -0.508 0.9398)
			(end 0.508 -0.9398)
			(stroke
				(width 0)
				(type default)
			)
			(fill no)
			(layer "F.Fab")
		)
		(pad "1" smd custom
			(at 0 -0.4445 180)
			(size 0.1397 0.1397)
			(layers "F.Cu" "F.Mask" "F.Paste")
			(net "P1V8_STBY_VO")
			(options
				(clearance outline)
				(anchor circle)
			)
			(primitives
				(gr_poly
					(pts
						(arc
							(start -0.1778 -0.2794)
							(mid -0.249642 -0.249642)
							(end -0.2794 -0.1778)
						)
						(arc
							(start -0.2794 0.1778)
							(mid -0.249642 0.249642)
							(end -0.1778 0.2794)
						)
						(arc
							(start 0.1778 0.2794)
							(mid 0.249642 0.249642)
							(end 0.2794 0.1778)
						)
						(arc
							(start 0.2794 -0.1778)
							(mid 0.249642 -0.249642)
							(end 0.1778 -0.2794)
						)
					)
					(width 0)
					(fill yes)
				)
			)
		)
		(pad "2" smd custom
			(at 0 0.4445 180)
			(size 0.1397 0.1397)
			(layers "F.Cu" "F.Mask" "F.Paste")
			(net "P1V8_STBY_CC_R")
			(options
				(clearance outline)
				(anchor circle)
			)
			(primitives
				(gr_poly
					(pts
						(arc
							(start -0.1778 -0.2794)
							(mid -0.249642 -0.249642)
							(end -0.2794 -0.1778)
						)
						(arc
							(start -0.2794 0.1778)
							(mid -0.249642 0.249642)
							(end -0.1778 0.2794)
						)
						(arc
							(start 0.1778 0.2794)
							(mid 0.249642 0.249642)
							(end 0.2794 0.1778)
						)
						(arc
							(start 0.2794 -0.1778)
							(mid 0.249642 -0.249642)
							(end 0.1778 -0.2794)
						)
					)
					(width 0)
					(fill yes)
				)
			)
		)
	)
	(footprint ""
		(layer "F.Cu")
		(at 95.9358 -180.4416 90)
		(property "Reference" "C136"
			(at 0 0 90)
			(layer "F.SilkS")
			(hide yes)
			(effects
				(font
					(size 1.27 1.27)
				)
			)
		)
		(property "Value" "SCD1U16V2KX-3GP"
			(at 1.1811 -2.7051 90)
			(unlocked yes)
			(layer "F.Fab")
			(hide yes)
			(effects
				(font
					(size 1.016 1.016)
					(thickness 0.1524)
				)
			)
		)
		(property "Device Type" "C402H22"
			(at 1.1811 -4.2291 90)
			(unlocked yes)
			(layer "F.Fab")
			(hide yes)
			(effects
				(font
					(size 1.016 1.016)
					(thickness 0.1524)
				)
			)
		)
		(duplicate_pad_numbers_are_jumpers no)
		(fp_rect
			(start -0.4318 0.9525)
			(end 0.4318 -0.9525)
			(stroke
				(width 0)
				(type default)
			)
			(fill no)
			(layer "F.CrtYd")
		)
		(fp_rect
			(start -0.4318 0.9525)
			(end 0.4318 -0.9525)
			(stroke
				(width 0)
				(type default)
			)
			(fill no)
			(layer "F.Fab")
		)
		(pad "1" smd custom
			(at 0 -0.4445 90)
			(size 0.1524 0.1524)
			(layers "F.Cu" "F.Mask" "F.Paste")
			(net "P3V3_STBY")
			(options
				(clearance outline)
				(anchor circle)
			)
			(primitives
				(gr_poly
					(pts
						(arc
							(start 0.3048 -0.2032)
							(mid 0.275042 -0.275042)
							(end 0.2032 -0.3048)
						)
						(arc
							(start -0.2032 -0.3048)
							(mid -0.275042 -0.275042)
							(end -0.3048 -0.2032)
						)
						(arc
							(start -0.3048 0.2032)
							(mid -0.275042 0.275042)
							(end -0.2032 0.3048)
						)
						(arc
							(start 0.2032 0.3048)
							(mid 0.275042 0.275042)
							(end 0.3048 0.2032)
						)
					)
					(width 0)
					(fill yes)
				)
			)
		)
		(pad "2" smd custom
			(at 0 0.4445 90)
			(size 0.1524 0.1524)
			(layers "F.Cu" "F.Mask" "F.Paste")
			(net "GND")
			(options
				(clearance outline)
				(anchor circle)
			)
			(primitives
				(gr_poly
					(pts
						(arc
							(start 0.3048 -0.2032)
							(mid 0.275042 -0.275042)
							(end 0.2032 -0.3048)
						)
						(arc
							(start -0.2032 -0.3048)
							(mid -0.275042 -0.275042)
							(end -0.3048 -0.2032)
						)
						(arc
							(start -0.3048 0.2032)
							(mid -0.275042 0.275042)
							(end -0.2032 0.3048)
						)
						(arc
							(start 0.2032 0.3048)
							(mid 0.275042 0.275042)
							(end 0.3048 0.2032)
						)
					)
					(width 0)
					(fill yes)
				)
			)
		)
	)
	(footprint ""
		(layer "F.Cu")
		(at 86.880192 -57.916318 -90)
		(property "Reference" "R3"
			(at 0 0 270)
			(layer "F.SilkS")
			(hide yes)
			(effects
				(font
					(size 1.27 1.27)
				)
			)
		)
		(property "Value" "4K7R2F-GP"
			(at 0.064008 -3.993896 270)
			(unlocked yes)
			(layer "F.Fab")
			(hide yes)
			(effects
				(font
					(size 1.016 1.016)
					(thickness 0.1524)
				)
			)
		)
		(property "Device Type" "R402H16"
			(at 0.064008 -5.517896 270)
			(unlocked yes)
			(layer "F.Fab")
			(hide yes)
			(effects
				(font
					(size 1.016 1.016)
					(thickness 0.1524)
				)
			)
		)
		(duplicate_pad_numbers_are_jumpers no)
		(fp_line
			(start -0.508 -0.9398)
			(end -0.508 0.9398)
			(stroke
				(width 0.1524)
				(type default)
			)
			(layer "F.SilkS")
		)
		(fp_line
			(start 0.508 -0.9398)
			(end -0.508 -0.9398)
			(stroke
				(width 0.1524)
				(type default)
			)
			(layer "F.SilkS")
		)
		(fp_rect
			(start -0.508 0.9398)
			(end 0.508 -0.9398)
			(stroke
				(width 0)
				(type default)
			)
			(fill no)
			(layer "F.CrtYd")
		)
		(fp_rect
			(start -0.508 0.9398)
			(end 0.508 -0.9398)
			(stroke
				(width 0)
				(type default)
			)
			(fill no)
			(layer "F.Fab")
		)
		(pad "1" smd custom
			(at 0 -0.4445 270)
			(size 0.1397 0.1397)
			(layers "F.Cu" "F.Mask" "F.Paste")
			(net "I2C_MEZZ_ALERT_N")
			(options
				(clearance outline)
				(anchor circle)
			)
			(primitives
				(gr_poly
					(pts
						(arc
							(start -0.1778 -0.2794)
							(mid -0.249642 -0.249642)
							(end -0.2794 -0.1778)
						)
						(arc
							(start -0.2794 0.1778)
							(mid -0.249642 0.249642)
							(end -0.1778 0.2794)
						)
						(arc
							(start 0.1778 0.2794)
							(mid 0.249642 0.249642)
							(end 0.2794 0.1778)
						)
						(arc
							(start 0.2794 -0.1778)
							(mid 0.249642 -0.249642)
							(end 0.1778 -0.2794)
						)
					)
					(width 0)
					(fill yes)
				)
			)
		)
		(pad "2" smd custom
			(at 0 0.4445 270)
			(size 0.1397 0.1397)
			(layers "F.Cu" "F.Mask" "F.Paste")
			(net "P3V3_STBY")
			(options
				(clearance outline)
				(anchor circle)
			)
			(primitives
				(gr_poly
					(pts
						(arc
							(start -0.1778 -0.2794)
							(mid -0.249642 -0.249642)
							(end -0.2794 -0.1778)
						)
						(arc
							(start -0.2794 0.1778)
							(mid -0.249642 0.249642)
							(end -0.1778 0.2794)
						)
						(arc
							(start 0.1778 0.2794)
							(mid 0.249642 0.249642)
							(end 0.2794 0.1778)
						)
						(arc
							(start 0.2794 -0.1778)
							(mid 0.249642 -0.249642)
							(end 0.1778 -0.2794)
						)
					)
					(width 0)
					(fill yes)
				)
			)
		)
	)
	(footprint ""
		(layer "F.Cu")
		(at 37.299646 -174.67961 90)
		(property "Reference" "C184"
			(at 0 0 90)
			(layer "F.SilkS")
			(hide yes)
			(effects
				(font
					(size 1.27 1.27)
				)
			)
		)
		(property "Value" "SC68P50V2JN-2-GP"
			(at 1.1811 -2.7051 90)
			(unlocked yes)
			(layer "F.Fab")
			(hide yes)
			(effects
				(font
					(size 1.016 1.016)
					(thickness 0.1524)
				)
			)
		)
		(property "Device Type" "C402H22"
			(at 1.1811 -4.2291 90)
			(unlocked yes)
			(layer "F.Fab")
			(hide yes)
			(effects
				(font
					(size 1.016 1.016)
					(thickness 0.1524)
				)
			)
		)
		(duplicate_pad_numbers_are_jumpers no)
		(fp_rect
			(start -0.4318 0.9525)
			(end 0.4318 -0.9525)
			(stroke
				(width 0)
				(type default)
			)
			(fill no)
			(layer "F.CrtYd")
		)
		(fp_rect
			(start -0.4318 0.9525)
			(end 0.4318 -0.9525)
			(stroke
				(width 0)
				(type default)
			)
			(fill no)
			(layer "F.Fab")
		)
		(pad "1" smd custom
			(at 0 -0.4445 90)
			(size 0.1524 0.1524)
			(layers "F.Cu" "F.Mask" "F.Paste")
			(net "P3V3_STBY_VFB")
			(options
				(clearance outline)
				(anchor circle)
			)
			(primitives
				(gr_poly
					(pts
						(arc
							(start 0.3048 -0.2032)
							(mid 0.275042 -0.275042)
							(end 0.2032 -0.3048)
						)
						(arc
							(start -0.2032 -0.3048)
							(mid -0.275042 -0.275042)
							(end -0.3048 -0.2032)
						)
						(arc
							(start -0.3048 0.2032)
							(mid -0.275042 0.275042)
							(end -0.2032 0.3048)
						)
						(arc
							(start 0.2032 0.3048)
							(mid 0.275042 0.275042)
							(end 0.3048 0.2032)
						)
					)
					(width 0)
					(fill yes)
				)
			)
		)
		(pad "2" smd custom
			(at 0 0.4445 90)
			(size 0.1524 0.1524)
			(layers "F.Cu" "F.Mask" "F.Paste")
			(net "P3V3_STBY_VFB_R")
			(options
				(clearance outline)
				(anchor circle)
			)
			(primitives
				(gr_poly
					(pts
						(arc
							(start 0.3048 -0.2032)
							(mid 0.275042 -0.275042)
							(end 0.2032 -0.3048)
						)
						(arc
							(start -0.2032 -0.3048)
							(mid -0.275042 -0.275042)
							(end -0.3048 -0.2032)
						)
						(arc
							(start -0.3048 0.2032)
							(mid -0.275042 0.275042)
							(end -0.2032 0.3048)
						)
						(arc
							(start 0.2032 0.3048)
							(mid 0.275042 0.275042)
							(end 0.3048 0.2032)
						)
					)
					(width 0)
					(fill yes)
				)
			)
		)
	)
	(footprint ""
		(layer "F.Cu")
		(at 88.31072 -162.042856 180)
		(property "Reference" "R28"
			(at 0 0 180)
			(layer "F.SilkS")
			(hide yes)
			(effects
				(font
					(size 1.27 1.27)
				)
			)
		)
		(property "Value" "12KR2J-L-GP"
			(at 0.064008 -3.993896 180)
			(unlocked yes)
			(layer "F.Fab")
			(hide yes)
			(effects
				(font
					(size 1.016 1.016)
					(thickness 0.1524)
				)
			)
		)
		(property "Device Type" "R402H16"
			(at 0.064008 -5.517896 180)
			(unlocked yes)
			(layer "F.Fab")
			(hide yes)
			(effects
				(font
					(size 1.016 1.016)
					(thickness 0.1524)
				)
			)
		)
		(duplicate_pad_numbers_are_jumpers no)
		(fp_line
			(start 0.508 -0.9398)
			(end -0.508 -0.9398)
			(stroke
				(width 0.1524)
				(type default)
			)
			(layer "F.SilkS")
		)
		(fp_line
			(start -0.508 -0.9398)
			(end -0.508 0.9398)
			(stroke
				(width 0.1524)
				(type default)
			)
			(layer "F.SilkS")
		)
		(fp_rect
			(start -0.508 0.9398)
			(end 0.508 -0.9398)
			(stroke
				(width 0)
				(type default)
			)
			(fill no)
			(layer "F.CrtYd")
		)
		(fp_rect
			(start -0.508 0.9398)
			(end 0.508 -0.9398)
			(stroke
				(width 0)
				(type default)
			)
			(fill no)
			(layer "F.Fab")
		)
		(pad "1" smd custom
			(at 0 -0.4445 180)
			(size 0.1397 0.1397)
			(layers "F.Cu" "F.Mask" "F.Paste")
			(net "RBIAS")
			(options
				(clearance outline)
				(anchor circle)
			)
			(primitives
				(gr_poly
					(pts
						(arc
							(start -0.1778 -0.2794)
							(mid -0.249642 -0.249642)
							(end -0.2794 -0.1778)
						)
						(arc
							(start -0.2794 0.1778)
							(mid -0.249642 0.249642)
							(end -0.1778 0.2794)
						)
						(arc
							(start 0.1778 0.2794)
							(mid 0.249642 0.249642)
							(end 0.2794 0.1778)
						)
						(arc
							(start 0.2794 -0.1778)
							(mid 0.249642 -0.249642)
							(end 0.1778 -0.2794)
						)
					)
					(width 0)
					(fill yes)
				)
			)
		)
		(pad "2" smd custom
			(at 0 0.4445 180)
			(size 0.1397 0.1397)
			(layers "F.Cu" "F.Mask" "F.Paste")
			(net "GND")
			(options
				(clearance outline)
				(anchor circle)
			)
			(primitives
				(gr_poly
					(pts
						(arc
							(start -0.1778 -0.2794)
							(mid -0.249642 -0.249642)
							(end -0.2794 -0.1778)
						)
						(arc
							(start -0.2794 0.1778)
							(mid -0.249642 0.249642)
							(end -0.1778 0.2794)
						)
						(arc
							(start 0.1778 0.2794)
							(mid 0.249642 0.249642)
							(end 0.2794 0.1778)
						)
						(arc
							(start 0.2794 -0.1778)
							(mid 0.249642 -0.249642)
							(end 0.1778 -0.2794)
						)
					)
					(width 0)
					(fill yes)
				)
			)
		)
	)
	(footprint ""
		(layer "F.Cu")
		(at 84.986622 -78.951836 90)
		(property "Reference" "VIA11"
			(at 0 0 90)
			(layer "F.SilkS")
			(hide yes)
			(effects
				(font
					(size 1.27 1.27)
				)
			)
		)
		(property "Value" "85OHM-8L-1D6MM-L16L18-GP"
			(at 4.064 0.6096 90)
			(unlocked yes)
			(layer "F.Fab")
			(hide yes)
			(effects
				(font
					(size 1.016 1.016)
					(thickness 0.1524)
				)
			)
		)
		(property "Device Type" "VIA-PCIE-4P-368076"
			(at 4.064 -0.9144 90)
			(unlocked yes)
			(layer "F.Fab")
			(hide yes)
			(effects
				(font
					(size 1.016 1.016)
					(thickness 0.1524)
				)
			)
		)
		(duplicate_pad_numbers_are_jumpers no)
		(fp_rect
			(start -1.8415 0.381)
			(end 1.8415 -0.381)
			(stroke
				(width 0)
				(type default)
			)
			(fill no)
			(layer "F.CrtYd")
		)
		(fp_rect
			(start -1.8415 0.381)
			(end 1.8415 -0.381)
			(stroke
				(width 0)
				(type default)
			)
			(fill no)
			(layer "F.Fab")
		)
		(pad "1" thru_hole circle
			(at -1.4605 0 90)
			(size 0.508 0.508)
			(drill 0.254)
			(layers "*.Cu" "*.Mask")
			(remove_unused_layers no)
			(net "GND")
			(clearance 0.127)
			(thermal_gap 0.127)
		)
		(pad "2" thru_hole circle
			(at -0.4445 0 90)
			(size 0.508 0.508)
			(drill 0.254)
			(layers "*.Cu" "*.Mask")
			(remove_unused_layers no)
			(net "PCIE_IOM_TO_COMP_18_DP")
			(clearance 0.127)
			(thermal_gap 0.127)
		)
		(pad "3" thru_hole circle
			(at 0.4445 0 90)
			(size 0.508 0.508)
			(drill 0.254)
			(layers "*.Cu" "*.Mask")
			(remove_unused_layers no)
			(net "PCIE_IOM_TO_COMP_18_DN")
			(clearance 0.127)
			(thermal_gap 0.127)
		)
		(pad "4" thru_hole circle
			(at 1.4605 0 90)
			(size 0.508 0.508)
			(drill 0.254)
			(layers "*.Cu" "*.Mask")
			(remove_unused_layers no)
			(net "GND")
			(clearance 0.127)
			(thermal_gap 0.127)
		)
	)
)
